(kicad_pcb
	(version 20241229)
	(generator "pcbnew")
	(generator_version "9.0")
	(general
		(thickness 0.761)
		(legacy_teardrops no)
	)
	(paper "A4")
	(title_block
		(title " M.2 to OCuLink adapter")
		(date "2025-07-16")
		(rev "1.0.2")
		(company "Antmicro Ltd")
		(comment 1 "www.antmicro.com")
		(comment 9 "footprints 5-6 of 22")
	)
	(layers
		(0 "F.Cu" signal)
		(4 "In1.Cu" signal)
		(6 "In2.Cu" signal)
		(2 "B.Cu" signal)
		(9 "F.Adhes" user "F.Adhesive")
		(11 "B.Adhes" user "B.Adhesive")
		(13 "F.Paste" user)
		(15 "B.Paste" user)
		(5 "F.SilkS" user "F.Silkscreen")
		(7 "B.SilkS" user "B.Silkscreen")
		(1 "F.Mask" user)
		(3 "B.Mask" user)
		(17 "Dwgs.User" user "User.Drawings")
		(19 "Cmts.User" user "User.Comments")
		(21 "Eco1.User" user "User.Eco1")
		(23 "Eco2.User" user "User.Eco2")
		(25 "Edge.Cuts" user)
		(27 "Margin" user)
		(31 "F.CrtYd" user "F.Courtyard")
		(29 "B.CrtYd" user "B.Courtyard")
		(35 "F.Fab" user)
		(33 "B.Fab" user)
	)
	(footprint "antmicro-footprints:Amphenol_G14A421211112HR"
		(locked yes)
		(layer "F.Cu")
		(at 146.017041 98.587904)
		(property "Reference" "J2"
			(at 4.592959 0.202096 0)
			(unlocked yes)
			(layer "F.SilkS")
			(effects
				(font
					(size 0.7 0.7)
					(thickness 0.15)
				)
				(justify left bottom)
			)
		)
		(property "Value" "OCuLink_x4_Amphenol_G14A421211112HR"
			(at 0 6.385 0)
			(unlocked yes)
			(layer "F.Fab")
			(effects
				(font
					(size 0.7 0.7)
					(thickness 0.15)
				)
				(justify left bottom)
			)
		)
		(property "Datasheet" "https://cdn.amphenol-cs.com/media/wysiwyg/files/drawing/g14a421x1bxxxhr.pdf"
			(at 0 0 0)
			(layer "F.Fab")
			(hide yes)
			(effects
				(font
					(size 1.27 1.27)
					(thickness 0.15)
				)
			)
		)
		(property "Description" "I/O Connectors OCulink, Receptacle, 0.5mm pitch, 4X, R/A SMT with shell leg SMT type, 30U\" gold plating, LCP, black, T&R packing"
			(at 0 0 0)
			(layer "F.Fab")
			(hide yes)
			(effects
				(font
					(size 1.27 1.27)
					(thickness 0.15)
				)
			)
		)
		(property "Manufacturer" "Amphenol"
			(at 0 0 0)
			(unlocked yes)
			(layer "F.Fab")
			(hide yes)
			(effects
				(font
					(size 1 1)
					(thickness 0.15)
				)
			)
		)
		(property "MPN" "G14A421211112HR"
			(at 0 0 0)
			(unlocked yes)
			(layer "F.Fab")
			(hide yes)
			(effects
				(font
					(size 1 1)
					(thickness 0.15)
				)
			)
		)
		(property "Author" "Antmicro"
			(at 0 0 0)
			(unlocked yes)
			(layer "F.Fab")
			(hide yes)
			(effects
				(font
					(size 1 1)
					(thickness 0.15)
				)
			)
		)
		(property "License" "Apache-2.0"
			(at 0 0 0)
			(unlocked yes)
			(layer "F.Fab")
			(hide yes)
			(effects
				(font
					(size 1 1)
					(thickness 0.15)
				)
			)
		)
		(sheetname "/")
		(sheetfile "antmicro-m2-oculink-adapter-hw.kicad_sch")
		(solder_paste_margin -0.06)
		(attr smd)
		(fp_line
			(start -6.8 -0.4)
			(end -6.8 -3)
			(stroke
				(width 0.1)
				(type default)
			)
			(layer "F.SilkS")
		)
		(fp_line
			(start 6.8 -3)
			(end 6.8 -0.4)
			(stroke
				(width 0.1)
				(type default)
			)
			(layer "F.SilkS")
		)
		(fp_circle
			(center -5.3 -5.52)
			(end -5.25 -5.52)
			(stroke
				(width 0.15)
				(type solid)
			)
			(fill yes)
			(layer "F.SilkS")
		)
		(fp_rect
			(start -8.22 -5.22)
			(end 8.22 4.94)
			(stroke
				(width 0.05)
				(type solid)
			)
			(fill no)
			(layer "F.CrtYd")
		)
		(fp_line
			(start 7 3.065)
			(end -7 3.065)
			(stroke
				(width 0.1)
				(type default)
			)
			(layer "F.Fab")
		)
		(fp_text user "Author: Antmicro"
			(at -8.22 11.085 0)
			(layer "F.Fab")
			(effects
				(font
					(size 0.7 0.7)
					(thickness 0.15)
				)
				(justify left bottom)
			)
		)
		(fp_text user "License: Apache-2.0"
			(at -8.22 12.285 0)
			(layer "F.Fab")
			(effects
				(font
					(size 0.7 0.7)
					(thickness 0.15)
				)
				(justify left bottom)
			)
		)
		(fp_text user "PCB EDGE"
			(at 2.8 2.95 0)
			(unlocked yes)
			(layer "F.Fab")
			(effects
				(font
					(size 0.5 0.5)
					(thickness 0.125)
				)
				(justify left bottom)
			)
		)
		(fp_text user "${REFERENCE}"
			(at -8.22 9.885 0)
			(unlocked yes)
			(layer "F.Fab")
			(effects
				(font
					(size 0.7 0.7)
					(thickness 0.15)
				)
				(justify left bottom)
			)
		)
		(pad "" np_thru_hole circle
			(at -5.42 -1.395 90)
			(size 1 1)
			(drill 1)
			(layers "F&B.Cu" "*.Mask")
		)
		(pad "" np_thru_hole circle
			(at 5.95 -1.395 90)
			(size 1 1)
			(drill 1)
			(layers "F&B.Cu" "*.Mask")
		)
		(pad "A1" smd roundrect
			(at -4.75 -2.115 90)
			(size 0.91 0.28)
			(layers "F.Cu" "F.Mask" "F.Paste")
			(roundrect_rratio 0.5)
			(net 17 "+3V3")
			(pinfunction "V_{ACT}_RX_3V3")
			(pintype "power_in")
		)
		(pad "A2" smd roundrect
			(at -4.25 -2.115 90)
			(size 0.91 0.28)
			(layers "F.Cu" "F.Mask" "F.Paste")
			(roundrect_rratio 0.5)
			(net 1 "GND")
			(pinfunction "GND")
			(pintype "passive")
		)
		(pad "A3" smd roundrect
			(at -3.75 -2.115 90)
			(size 0.91 0.28)
			(layers "F.Cu" "F.Mask" "F.Paste")
			(roundrect_rratio 0.5)
			(net 26 "/PCIe_{x4}.RX0+")
			(pinfunction "PER0+")
			(pintype "output")
		)
		(pad "A4" smd roundrect
			(at -3.25 -2.115 90)
			(size 0.91 0.28)
			(layers "F.Cu" "F.Mask" "F.Paste")
			(roundrect_rratio 0.5)
			(net 7 "/PCIe_{x4}.RX0-")
			(pinfunction "PER0-")
			(pintype "output")
		)
		(pad "A5" smd roundrect
			(at -2.75 -2.115 90)
			(size 0.91 0.28)
			(layers "F.Cu" "F.Mask" "F.Paste")
			(roundrect_rratio 0.5)
			(net 1 "GND")
			(pinfunction "GND")
			(pintype "passive")
		)
		(pad "A6" smd roundrect
			(at -2.25 -2.115 90)
			(size 0.91 0.28)
			(layers "F.Cu" "F.Mask" "F.Paste")
			(roundrect_rratio 0.5)
			(net 16 "/PCIe_{x4}.RX1+")
			(pinfunction "PER1+")
			(pintype "output")
		)
		(pad "A7" smd roundrect
			(at -1.75 -2.115 90)
			(size 0.91 0.28)
			(layers "F.Cu" "F.Mask" "F.Paste")
			(roundrect_rratio 0.5)
			(net 27 "/PCIe_{x4}.RX1-")
			(pinfunction "PER1-")
			(pintype "output")
		)
		(pad "A8" smd roundrect
			(at -1.25 -2.115 90)
			(size 0.91 0.28)
			(layers "F.Cu" "F.Mask" "F.Paste")
			(roundrect_rratio 0.5)
			(net 1 "GND")
			(pinfunction "GND")
			(pintype "passive")
		)
		(pad "A9" smd roundrect
			(at -0.75 -2.115 90)
			(size 0.91 0.28)
			(layers "F.Cu" "F.Mask" "F.Paste")
			(roundrect_rratio 0.5)
			(net 52 "unconnected-(J2-NC-PadA9)")
			(pinfunction "NC")
			(pintype "no_connect")
		)
		(pad "A10" smd roundrect
			(at -0.25 -2.115 90)
			(size 0.91 0.28)
			(layers "F.Cu" "F.Mask" "F.Paste")
			(roundrect_rratio 0.5)
			(net 24 "/~{WAKEC}")
			(pinfunction "~{CWAKE}")
			(pintype "bidirectional")
		)
		(pad "A11" smd roundrect
			(at 0.25 -2.115 90)
			(size 0.91 0.28)
			(layers "F.Cu" "F.Mask" "F.Paste")
			(roundrect_rratio 0.5)
			(net 1 "GND")
			(pinfunction "GND")
			(pintype "passive")
		)
		(pad "A12" smd roundrect
			(at 0.75 -2.115 90)
			(size 0.91 0.28)
			(layers "F.Cu" "F.Mask" "F.Paste")
			(roundrect_rratio 0.5)
			(net 13 "/PCIe_{REF0}_R.CK+")
			(pinfunction "VSP1")
			(pintype "bidirectional")
		)
		(pad "A13" smd roundrect
			(at 1.25 -2.115 90)
			(size 0.91 0.28)
			(layers "F.Cu" "F.Mask" "F.Paste")
			(roundrect_rratio 0.5)
			(net 12 "/PCIe_{REF0}_R.CK-")
			(pinfunction "VSP2")
			(pintype "bidirectional")
		)
		(pad "A14" smd roundrect
			(at 1.75 -2.115 90)
			(size 0.91 0.28)
			(layers "F.Cu" "F.Mask" "F.Paste")
			(roundrect_rratio 0.5)
			(net 1 "GND")
			(pinfunction "GND")
			(pintype "passive")
		)
		(pad "A15" smd roundrect
			(at 2.25 -2.115 90)
			(size 0.91 0.28)
			(layers "F.Cu" "F.Mask" "F.Paste")
			(roundrect_rratio 0.5)
			(net 4 "/PCIe_{x4}.RX2+")
			(pinfunction "PER2+")
			(pintype "output")
		)
		(pad "A16" smd roundrect
			(at 2.75 -2.115 90)
			(size 0.91 0.28)
			(layers "F.Cu" "F.Mask" "F.Paste")
			(roundrect_rratio 0.5)
			(net 14 "/PCIe_{x4}.RX2-")
			(pinfunction "PER2-")
			(pintype "output")
		)
		(pad "A17" smd roundrect
			(at 3.25 -2.115 90)
			(size 0.91 0.28)
			(layers "F.Cu" "F.Mask" "F.Paste")
			(roundrect_rratio 0.5)
			(net 1 "GND")
			(pinfunction "GND")
			(pintype "passive")
		)
		(pad "A18" smd roundrect
			(at 3.75 -2.115 90)
			(size 0.91 0.28)
			(layers "F.Cu" "F.Mask" "F.Paste")
			(roundrect_rratio 0.5)
			(net 9 "/PCIe_{x4}.RX3+")
			(pinfunction "PER3+")
			(pintype "output")
		)
		(pad "A19" smd roundrect
			(at 4.25 -2.115 90)
			(size 0.91 0.28)
			(layers "F.Cu" "F.Mask" "F.Paste")
			(roundrect_rratio 0.5)
			(net 6 "/PCIe_{x4}.RX3-")
			(pinfunction "PER3-")
			(pintype "output")
		)
		(pad "A20" smd roundrect
			(at 4.75 -2.115 90)
			(size 0.91 0.28)
			(layers "F.Cu" "F.Mask" "F.Paste")
			(roundrect_rratio 0.5)
			(net 1 "GND")
			(pinfunction "GND")
			(pintype "passive")
		)
		(pad "A21" smd roundrect
			(at 5.25 -2.115 90)
			(size 0.91 0.28)
			(layers "F.Cu" "F.Mask" "F.Paste")
			(roundrect_rratio 0.5)
			(net 50 "Net-(J2-5V-PadA21)")
			(pinfunction "5V")
			(pintype "passive")
		)
		(pad "B1" smd roundrect
			(at -5.25 -4.305 90)
			(size 0.91 0.28)
			(layers "F.Cu" "F.Mask" "F.Paste")
			(roundrect_rratio 0.5)
			(net 50 "Net-(J2-5V-PadA21)")
			(pinfunction "5V")
			(pintype "passive")
		)
		(pad "B2" smd roundrect
			(at -4.75 -4.305 90)
			(size 0.91 0.28)
			(layers "F.Cu" "F.Mask" "F.Paste")
			(roundrect_rratio 0.5)
			(net 1 "GND")
			(pinfunction "GND")
			(pintype "passive")
		)
		(pad "B3" smd roundrect
			(at -4.25 -4.305 90)
			(size 0.91 0.28)
			(layers "F.Cu" "F.Mask" "F.Paste")
			(roundrect_rratio 0.5)
			(net 25 "/PCIe_{x4}.TX0+")
			(pinfunction "PET0+")
			(pintype "input")
		)
		(pad "B4" smd roundrect
			(at -3.75 -4.305 90)
			(size 0.91 0.28)
			(layers "F.Cu" "F.Mask" "F.Paste")
			(roundrect_rratio 0.5)
			(net 15 "/PCIe_{x4}.TX0-")
			(pinfunction "PET0-")
			(pintype "input")
		)
		(pad "B5" smd roundrect
			(at -3.25 -4.305 90)
			(size 0.91 0.28)
			(layers "F.Cu" "F.Mask" "F.Paste")
			(roundrect_rratio 0.5)
			(net 1 "GND")
			(pinfunction "GND")
			(pintype "passive")
		)
		(pad "B6" smd roundrect
			(at -2.75 -4.305 90)
			(size 0.91 0.28)
			(layers "F.Cu" "F.Mask" "F.Paste")
			(roundrect_rratio 0.5)
			(net 3 "/PCIe_{x4}.TX1+")
			(pinfunction "PET1+")
			(pintype "input")
		)
		(pad "B7" smd roundrect
			(at -2.25 -4.305 90)
			(size 0.91 0.28)
			(layers "F.Cu" "F.Mask" "F.Paste")
			(roundrect_rratio 0.5)
			(net 8 "/PCIe_{x4}.TX1-")
			(pinfunction "PET1-")
			(pintype "input")
		)
		(pad "B8" smd roundrect
			(at -1.75 -4.305 90)
			(size 0.91 0.28)
			(layers "F.Cu" "F.Mask" "F.Paste")
			(roundrect_rratio 0.5)
			(net 1 "GND")
			(pinfunction "GND")
			(pintype "passive")
		)
		(pad "B9" smd roundrect
			(at -1.25 -4.305 90)
			(size 0.91 0.28)
			(layers "F.Cu" "F.Mask" "F.Paste")
			(roundrect_rratio 0.5)
			(net 53 "unconnected-(J2-SCL-PadB9)")
			(pinfunction "SCL")
			(pintype "bidirectional+no_connect")
		)
		(pad "B10" smd roundrect
			(at -0.75 -4.305 90)
			(size 0.91 0.28)
			(layers "F.Cu" "F.Mask" "F.Paste")
			(roundrect_rratio 0.5)
			(net 51 "/~{WAKE_C}_alt")
			(pinfunction "SDA")
			(pintype "bidirectional")
		)
		(pad "B11" smd roundrect
			(at -0.25 -4.305 90)
			(size 0.91 0.28)
			(layers "F.Cu" "F.Mask" "F.Paste")
			(roundrect_rratio 0.5)
			(net 1 "GND")
			(pinfunction "GND")
			(pintype "passive")
		)
		(pad "B12" smd roundrect
			(at 0.25 -4.305 90)
			(size 0.91 0.28)
			(layers "F.Cu" "F.Mask" "F.Paste")
			(roundrect_rratio 0.5)
			(net 23 "/~{PERSTC}")
			(pinfunction "~{PERST}")
			(pintype "bidirectional")
		)
		(pad "B13" smd roundrect
			(at 0.75 -4.305 90)
			(size 0.91 0.28)
			(layers "F.Cu" "F.Mask" "F.Paste")
			(roundrect_rratio 0.5)
			(net 54 "/~{CPRSNT}")
			(pinfunction "~{CPRSNT}")
			(pintype "bidirectional")
		)
		(pad "B14" smd roundrect
			(at 1.25 -4.305 90)
			(size 0.91 0.28)
			(layers "F.Cu" "F.Mask" "F.Paste")
			(roundrect_rratio 0.5)
			(net 1 "GND")
			(pinfunction "GND")
			(pintype "passive")
		)
		(pad "B15" smd roundrect
			(at 1.75 -4.305 90)
			(size 0.91 0.28)
			(layers "F.Cu" "F.Mask" "F.Paste")
			(roundrect_rratio 0.5)
			(net 5 "/PCIe_{x4}.TX2+")
			(pinfunction "PET2+")
			(pintype "input")
		)
		(pad "B16" smd roundrect
			(at 2.25 -4.305 90)
			(size 0.91 0.28)
			(layers "F.Cu" "F.Mask" "F.Paste")
			(roundrect_rratio 0.5)
			(net 10 "/PCIe_{x4}.TX2-")
			(pinfunction "PET2-")
			(pintype "input")
		)
		(pad "B17" smd roundrect
			(at 2.75 -4.305 90)
			(size 0.91 0.28)
			(layers "F.Cu" "F.Mask" "F.Paste")
			(roundrect_rratio 0.5)
			(net 1 "GND")
			(pinfunction "GND")
			(pintype "passive")
		)
		(pad "B18" smd roundrect
			(at 3.25 -4.305 90)
			(size 0.91 0.28)
			(layers "F.Cu" "F.Mask" "F.Paste")
			(roundrect_rratio 0.5)
			(net 2 "/PCIe_{x4}.TX3+")
			(pinfunction "PET3+")
			(pintype "input")
		)
		(pad "B19" smd roundrect
			(at 3.75 -4.305 90)
			(size 0.91 0.28)
			(layers "F.Cu" "F.Mask" "F.Paste")
			(roundrect_rratio 0.5)
			(net 21 "/PCIe_{x4}.TX3-")
			(pinfunction "PET3-")
			(pintype "input")
		)
		(pad "B20" smd roundrect
			(at 4.25 -4.305 90)
			(size 0.91 0.28)
			(layers "F.Cu" "F.Mask" "F.Paste")
			(roundrect_rratio 0.5)
			(net 1 "GND")
			(pinfunction "GND")
			(pintype "passive")
		)
		(pad "B21" smd roundrect
			(at 4.75 -4.305 90)
			(size 0.91 0.28)
			(layers "F.Cu" "F.Mask" "F.Paste")
			(roundrect_rratio 0.5)
			(net 57 "Net-(J2-V_{ACT}_TX_3V3)")
			(pinfunction "V_{ACT}_TX_3V3")
			(pintype "power_in")
		)
		(pad "SH" smd roundrect
			(at -6.91 -3.915 90)
			(size 1.38 1.81)
			(layers "F.Cu" "F.Mask" "F.Paste")
			(roundrect_rratio 0.1)
			(net 1 "GND")
			(pinfunction "SH")
			(pintype "passive")
		)
		(pad "SH" smd roundrect
			(at -6.91 0.805 90)
			(size 1.81 1.8)
			(layers "F.Cu" "F.Mask" "F.Paste")
			(roundrect_rratio 0.1)
			(net 1 "GND")
			(pinfunction "SH")
			(pintype "passive")
		)
		(pad "SH" smd roundrect
			(at 6.91 -3.915 90)
			(size 1.38 1.81)
			(layers "F.Cu" "F.Mask" "F.Paste")
			(roundrect_rratio 0.1)
			(net 1 "GND")
			(pinfunction "SH")
			(pintype "passive")
		)
		(pad "SH" smd roundrect
			(at 6.91 0.805 90)
			(size 1.81 1.8)
			(layers "F.Cu" "F.Mask" "F.Paste")
			(roundrect_rratio 0.1)
			(net 1 "GND")
			(pinfunction "SH")
			(pintype "passive")
		)
	)
	(footprint "antmicro-footprints:R_0201"
		(layer "F.Cu")
		(at 146.08 92.63 -90)
		(descr "Resistor SMD 0201")
		(tags "resistor SMD 0201")
		(property "Reference" "R10"
			(at -1.14 0.44 180)
			(layer "F.SilkS")
			(effects
				(font
					(size 0.7 0.7)
					(thickness 0.15)
				)
				(justify right top)
			)
		)
		(property "Value" "R_0R_0201"
			(at 0 1.25 90)
			(layer "F.Fab")
			(effects
				(font
					(size 0.7 0.7)
					(thickness 0.15)
				)
				(justify right top)
			)
		)
		(property "Datasheet" "https://www.bourns.com/docs/product-datasheets/cr.pdf"
			(at 0 0 90)
			(layer "F.Fab")
			(hide yes)
			(effects
				(font
					(size 1.27 1.27)
					(thickness 0.15)
				)
			)
		)
		(property "Description" "SMD Chip Resistor"
			(at 0 0 90)
			(layer "F.Fab")
			(hide yes)
			(effects
				(font
					(size 1.27 1.27)
					(thickness 0.15)
				)
			)
		)
		(property "MPN" "CR0201-FX-0R00GLF"
			(at 0 0 270)
			(unlocked yes)
			(layer "F.Fab")
			(hide yes)
			(effects
				(font
					(size 1 1)
					(thickness 0.15)
				)
			)
		)
		(property "Manufacturer" "Bourns"
			(at 0 0 270)
			(unlocked yes)
			(layer "F.Fab")
			(hide yes)
			(effects
				(font
					(size 1 1)
					(thickness 0.15)
				)
			)
		)
		(property "License" "Apache-2.0"
			(at 0 0 270)
			(unlocked yes)
			(layer "F.Fab")
			(hide yes)
			(effects
				(font
					(size 1 1)
					(thickness 0.15)
				)
			)
		)
		(property "Author" "Antmicro"
			(at 0 0 270)
			(unlocked yes)
			(layer "F.Fab")
			(hide yes)
			(effects
				(font
					(size 1 1)
					(thickness 0.15)
				)
			)
		)
		(property "Val" "0R"
			(at 0 0 270)
			(unlocked yes)
			(layer "F.Fab")
			(hide yes)
			(effects
				(font
					(size 1 1)
					(thickness 0.15)
				)
			)
		)
		(property "Tolerance" "1%"
			(at 0 0 270)
			(unlocked yes)
			(layer "F.Fab")
			(hide yes)
			(effects
				(font
					(size 1 1)
					(thickness 0.15)
				)
			)
		)
		(sheetname "/")
		(sheetfile "antmicro-m2-oculink-adapter-hw.kicad_sch")
		(attr smd)
		(fp_rect
			(start -0.7 -0.35)
			(end 0.7 0.35)
			(stroke
				(width 0.05)
				(type default)
			)
			(fill no)
			(layer "F.CrtYd")
		)
		(fp_rect
			(start -0.3 -0.15)
			(end 0.298 0.148)
			(stroke
				(width 0.15)
				(type solid)
			)
			(fill no)
			(layer "F.Fab")
		)
		(fp_text user "License: Apache-2.0"
			(at -0.71 4.25 90)
			(layer "F.Fab")
			(effects
				(font
					(size 0.7 0.7)
					(thickness 0.15)
				)
				(justify right top)
			)
		)
		(fp_text user "Author: Antmicro"
			(at -0.71 5.25 90)
			(layer "F.Fab")
			(effects
				(font
					(size 0.7 0.7)
					(thickness 0.15)
				)
				(justify right top)
			)
		)
		(fp_text user "${REFERENCE}"
			(at -0.71 3.25 90)
			(layer "F.Fab")
			(effects
				(font
					(size 0.7 0.7)
					(thickness 0.15)
				)
				(justify right top)
			)
		)
		(pad "" smd roundrect
			(at -0.346 0 270)
			(size 0.318 0.36)
			(layers "F.Paste")
			(roundrect_rratio 0.25)
		)
		(pad "" smd roundrect
			(at 0.344 0 270)
			(size 0.318 0.36)
			(layers "F.Paste")
			(roundrect_rratio 0.25)
		)
		(pad "1" smd roundrect
			(at -0.32 0 270)
			(size 0.46 0.4)
			(layers "F.Cu" "F.Mask")
			(roundrect_rratio 0.25)
			(net 55 "/~{PERST}")
			(pintype "passive")
		)
		(pad "2" smd roundrect
			(at 0.32 0 270)
			(size 0.46 0.4)
			(layers "F.Cu" "F.Mask")
			(roundrect_rratio 0.25)
			(net 23 "/~{PERSTC}")
			(pintype "passive")
		)
	)
)
